# S9S_MB_2U (Grand Teton) — schematic netlist excerpt (pin names and nets, part order shuffled) for the footprints in the layout excerpt that follows; sources: Cadence DE-HDL packaged netlist, KiCad conversion of 03242023_DA0F0TMBIJ0_F0T_Motherboard_J_brd_V01_OCP.brd

J26  SCONN288_ADR50017P087CC  SCONN288_ADR50017-P087CC IO  pkg DDR288S_1-1VXB  page 107
  VIN_BULK0  = P12V_S3_AUX_CPU1_NVDIMM
  RFU0  = TP_CHE_CPU1_DIMM2_FRU_0
  VIN_MGMT  = P3V3_AUX
  HSCL  = I3C_SPD_DDREFGH_CPU1_LVC1_SCL_1
  HSDA  = I3C_SPD_DDREFGH_CPU1_LVC1_SDA
  VSS0  = GND
  DQ0_A  = M_E_CPU1_SA_DQ<0>
  VSS1  = GND
  DQ1_A  = M_E_CPU1_SA_DQ<1>
  VSS2  = GND
  DQS0_A_T  = M_E_CPU1_SA_DQS_DP<0>
  DQS0_A_C  = M_E_CPU1_SA_DQS_DN<0>
  VSS3  = GND
  DQ4_A  = M_E_CPU1_SA_DQ<4>
  VSS4  = GND
  DQ5_A  = M_E_CPU1_SA_DQ<5>
  VSS5  = GND
  DQ8_A  = M_E_CPU1_SA_DQ<8>
  VSS6  = GND
  DQ9_A  = M_E_CPU1_SA_DQ<9>
  VSS7  = GND
  DQS1_A_T  = M_E_CPU1_SA_DQS_DP<1>
  DQS1_A_C  = M_E_CPU1_SA_DQS_DN<1>
  VSS8  = GND
  DQ12_A  = M_E_CPU1_SA_DQ<12>
  VSS9  = GND
  DQ13_A  = M_E_CPU1_SA_DQ<13>
  VSS10  = GND
  DQ16_A  = M_E_CPU1_SA_DQ<16>
  VSS11  = GND
  DQ17_A  = M_E_CPU1_SA_DQ<17>
  VSS12  = GND
  DQS2_A_T  = M_E_CPU1_SA_DQS_DP<2>
  DQS2_A_C  = M_E_CPU1_SA_DQS_DN<2>
  VSS13  = GND
  DQ20_A  = M_E_CPU1_SA_DQ<20>
  VSS14  = GND
  DQ21_A  = M_E_CPU1_SA_DQ<21>
  VSS15  = GND
  DQ24_A  = M_E_CPU1_SA_DQ<24>
  VSS16  = GND
  DQ25_A  = M_E_CPU1_SA_DQ<25>
  VSS17  = GND
  DQS3_A_T  = M_E_CPU1_SA_DQS_DP<3>
  DQS3_A_C  = M_E_CPU1_SA_DQS_DN<3>
  VSS18  = GND
  DQ28_A  = M_E_CPU1_SA_DQ<28>
  VSS19  = GND
  DQ29_A  = M_E_CPU1_SA_DQ<29>
  VSS20  = GND
  CB0_A  = M_E_CPU1_SA_CB<0>
  VSS21  = GND
  CB1_A  = M_E_CPU1_SA_CB<1>
  VSS22  = GND
  DQS4_A_T  = M_E_CPU1_SA_DQS_DP<4>
  DQS4_A_C  = M_E_CPU1_SA_DQS_DN<4>
  VSS23  = GND
  CB4_A  = M_E_CPU1_SA_CB<4>
  VSS24  = GND
  CB5_A  = M_E_CPU1_SA_CB<5>
  VSS25  = GND
  ALERT_N  = M_E_CPU1_ALERT_N
  VSS26  = GND
  CS0_A_N  = M_E_CPU1_SA_CS_N<2>
  VSS27  = GND
  CA0_A  = M_E_CPU1_SA_CA<0>
  VSS28  = GND
  CA2_A  = M_E_CPU1_SA_CA<2>
  VSS29  = GND
  CA4_A  = M_E_CPU1_SA_CA<4>
  VSS30  = GND
  CA6_A  = M_E_CPU1_SA_CA<6>
  VSS31  = GND
  PAR_A  = M_E_CPU1_SA_PAR
  VSS32  = GND
  CA0_B  = M_E_CPU1_SB_CA<0>
  VSS33  = GND
  CA2_B  = M_E_CPU1_SB_CA<2>
  VSS34  = GND
  CA4_B  = M_E_CPU1_SB_CA<4>
  VSS35  = GND
  CA6_B  = M_E_CPU1_SB_CA<6>
  VSS36  = GND
  CS0_B_N  = M_E_CPU1_SB_CS_N<2>
  VSS37  = GND
  \lbd||rsp_a_n\  = M_E_CPU1_SA_RSP<1>
  \lbs||rsp_b_n\  = M_E_CPU1_SB_RSP<1>
  VSS38  = GND
  CB4_B  = M_E_CPU1_SB_CB<4>
  VSS39  = GND
  CB5_B  = M_E_CPU1_SB_CB<5>
  VSS40  = GND
  \dqs9_b_t||tdqs9_b_t||dbi4_b_n\  = M_E_CPU1_SB_DQS_DP<9>
  \dqs9_b_c||tdqs9_b_c\  = M_E_CPU1_SB_DQS_DN<9>
  VSS41  = GND
  CB0_B  = M_E_CPU1_SB_CB<0>
  VSS42  = GND
  CB1_B  = M_E_CPU1_SB_CB<1>
  VSS43  = GND
  DQ0_B  = M_E_CPU1_SB_DQ<0>
  VSS44  = GND
  DQ1_B  = M_E_CPU1_SB_DQ<1>
  VSS45  = GND
  DQS0_B_T  = M_E_CPU1_SB_DQS_DP<0>
  DQS0_B_C  = M_E_CPU1_SB_DQS_DN<0>
  VSS46  = GND
  DQ4_B  = M_E_CPU1_SB_DQ<4>
  VSS47  = GND
  DQ5_B  = M_E_CPU1_SB_DQ<5>
  VSS48  = GND
  DQ8_B  = M_E_CPU1_SB_DQ<8>
  VSS49  = GND
  DQ9_B  = M_E_CPU1_SB_DQ<9>
  VSS50  = GND
  DQS1_B_T  = M_E_CPU1_SB_DQS_DP<1>
  DQS1_B_C  = M_E_CPU1_SB_DQS_DN<1>
  VSS51  = GND
  DQ12_B  = M_E_CPU1_SB_DQ<12>
  VSS52  = GND
  DQ13_B  = M_E_CPU1_SB_DQ<13>
  VSS53  = GND
  DQ16_B  = M_E_CPU1_SB_DQ<16>
  VSS54  = GND
  DQ17_B  = M_E_CPU1_SB_DQ<17>
  VSS55  = GND
  DQS2_B_T  = M_E_CPU1_SB_DQS_DP<2>
  DQS2_B_C  = M_E_CPU1_SB_DQS_DN<2>
  VSS56  = GND
  DQ20_B  = M_E_CPU1_SB_DQ<20>
  VSS57  = GND
  DQ21_B  = M_E_CPU1_SB_DQ<21>
  VSS58  = GND
  DQ24_B  = M_E_CPU1_SB_DQ<24>
  VSS59  = GND
  DQ25_B  = M_E_CPU1_SB_DQ<25>
  VSS60  = GND
  DQS3_B_T  = M_E_CPU1_SB_DQS_DP<3>
  DQS3_B_C  = M_E_CPU1_SB_DQS_DN<3>
  VSS61  = GND
  DQ28_B  = M_E_CPU1_SB_DQ<28>
  VSS62  = GND
  DQ29_B  = M_E_CPU1_SB_DQ<29>
  VSS63  = GND
  RFU1  = TP_CHE_CPU1_DIMM2_FRU_1
  VIN_BULK1  = P12V_S3_AUX_CPU1_NVDIMM
  VIN_BULK2  = P12V_S3_AUX_CPU1_NVDIMM
  \pwr_good||fail_n\  = PWRGD_CHE_CPU1_DIMM2
  HSA  = PD_CHE_CPU1_DIMM2_SAA
  RFU2  = TP_CHE_CPU1_DIMM2_FRU_2
  RFU3  = TP_CHE_CPU1_DIMM2_FRU_3
  VSS64  = GND
  DQ2_A  = M_E_CPU1_SA_DQ<2>
  VSS65  = GND
  DQ3_A  = M_E_CPU1_SA_DQ<3>
  VSS66  = GND
  \dqs5_a_c||tdqs5_a_c||dqs5_a_t||tdqs5_a_t\  = M_E_CPU1_SA_DQS_DN<5>
  \dqs5_a_t||tdqs5_a_t\  = M_E_CPU1_SA_DQS_DP<5>
  VSS67  = GND
  DQ6_A  = M_E_CPU1_SA_DQ<6>
  VSS68  = GND
  DQ7_A  = M_E_CPU1_SA_DQ<7>
  VSS69  = GND
  DQ10_A  = M_E_CPU1_SA_DQ<10>
  VSS70  = GND
  DQ11_A  = M_E_CPU1_SA_DQ<11>
  VSS71  = GND
  \dqs6_a_c||tdqs6_a_c||dqs6_a_t||tdqs6_a_t\  = M_E_CPU1_SA_DQS_DN<6>
  \dqs6_a_t||tdqs6_a_t\  = M_E_CPU1_SA_DQS_DP<6>
  VSS72  = GND
  DQ14_A  = M_E_CPU1_SA_DQ<14>
  VSS73  = GND
  DQ15_A  = M_E_CPU1_SA_DQ<15>
  VSS74  = GND
  DQ18_A  = M_E_CPU1_SA_DQ<18>
  VSS75  = GND
  DQ19_A  = M_E_CPU1_SA_DQ<19>
  VSS76  = GND
  \dqs7_a_c||tdqs7_a_c\  = M_E_CPU1_SA_DQS_DN<7>
  \dqs7_a_t||tdqs7_a_t\  = M_E_CPU1_SA_DQS_DP<7>
  VSS77  = GND
  DQ22_A  = M_E_CPU1_SA_DQ<22>
  VSS78  = GND
  DQ23_A  = M_E_CPU1_SA_DQ<23>
  VSS79  = GND
  DQ26_A  = M_E_CPU1_SA_DQ<26>
  VSS80  = GND
  DQ27_A  = M_E_CPU1_SA_DQ<27>
  VSS81  = GND
  \dqs8_a_c||tdqs8_a_c\  = M_E_CPU1_SA_DQS_DN<8>
  \dqs8_a_t||tdqs8_a_t\  = M_E_CPU1_SA_DQS_DP<8>
  VSS82  = GND
  DQ30_A  = M_E_CPU1_SA_DQ<30>
  VSS83  = GND
  DQ31_A  = M_E_CPU1_SA_DQ<31>
  VSS84  = GND
  CB2_A  = M_E_CPU1_SA_CB<2>
  VSS85  = GND
  CB3_A  = M_E_CPU1_SA_CB<3>
  VSS86  = GND
  \dqs9_a_c||tdqs9_a_c\  = M_E_CPU1_SA_DQS_DN<9>
  \dqs9_a_t||tdqs9_a_t\  = M_E_CPU1_SA_DQS_DP<9>
  VSS87  = GND
  CB6_A  = M_E_CPU1_SA_CB<6>
  VSS88  = GND
  CB7_A  = M_E_CPU1_SA_CB<7>
  VSS89  = GND
  RESET_N  = RST_M_EF_CPU1_FPGA_N
  VSS90  = GND
  CS1_A_N  = M_E_CPU1_SA_CS_N<3>
  VSS91  = GND
  CA1_A  = M_E_CPU1_SA_CA<1>
  VSS92  = GND
  CA3_A  = M_E_CPU1_SA_CA<3>
  VSS93  = GND
  CA5_A  = M_E_CPU1_SA_CA<5>
  VSS94  = GND
  CK_T  = M_E_CPU1_CLK_DP<1>
  CK_C  = M_E_CPU1_CLK_DN<1>
  VSS95  = GND
  RFU4  = TP_CHE_CPU1_DIMM2_FRU_4
  CA1_B  = M_E_CPU1_SB_CA<1>
  VSS96  = GND
  CA3_B  = M_E_CPU1_SB_CA<3>
  VSS97  = GND
  CA5_B  = M_E_CPU1_SB_CA<5>
  VSS98  = GND
  PAR_B  = M_E_CPU1_SB_PAR
  VSS99  = GND
  CS1_B_N  = M_E_CPU1_SB_CS_N<3>
  VSS100  = GND
  RFU5  = TP_CHE_CPU1_DIMM2_FRU_5
  RFU6  = TP_CHE_CPU1_DIMM2_FRU_6
  VSS101  = GND
  CB6_B  = M_E_CPU1_SB_CB<6>
  VSS102  = GND
  CB7_B  = M_E_CPU1_SB_CB<7>
  VSS103  = GND
  DQS4_B_C  = M_E_CPU1_SB_DQS_DN<4>
  DQS4_B_T  = M_E_CPU1_SB_DQS_DP<4>
  VSS104  = GND
  CB2_B  = M_E_CPU1_SB_CB<2>
  VSS105  = GND
  CB3_B  = M_E_CPU1_SB_CB<3>
  VSS106  = GND
  DQ2_B  = M_E_CPU1_SB_DQ<2>
  VSS107  = GND
  DQ3_B  = M_E_CPU1_SB_DQ<3>
  VSS108  = GND
  \dqs5_b_c||tdqs5_b_c\  = M_E_CPU1_SB_DQS_DN<5>
  \dqs5_b_t||tdqs5_b_t\  = M_E_CPU1_SB_DQS_DP<5>
  VSS109  = GND
  DQ6_B  = M_E_CPU1_SB_DQ<6>
  VSS110  = GND
  DQ7_B  = M_E_CPU1_SB_DQ<7>
  VSS111  = GND
  DQ10_B  = M_E_CPU1_SB_DQ<10>
  VSS112  = GND
  DQ11_B  = M_E_CPU1_SB_DQ<11>
  VSS113  = GND
  \dqs6_b_c||tdqs6_b_c\  = M_E_CPU1_SB_DQS_DN<6>
  \dqs6_b_t||tdqs6_b_t\  = M_E_CPU1_SB_DQS_DP<6>
  VSS114  = GND
  DQ14_B  = M_E_CPU1_SB_DQ<14>
  VSS115  = GND
  DQ15_B  = M_E_CPU1_SB_DQ<15>
  VSS116  = GND
  DQ18_B  = M_E_CPU1_SB_DQ<18>
  VSS117  = GND
  DQ19_B  = M_E_CPU1_SB_DQ<19>
  VSS118  = GND
  \dqs7_b_c||tdqs7_b_c\  = M_E_CPU1_SB_DQS_DN<7>
  \dqs7_b_t||tdqs7_b_t\  = M_E_CPU1_SB_DQS_DP<7>
  VSS119  = GND
  DQ22_B  = M_E_CPU1_SB_DQ<22>
  VSS120  = GND
  DQ23_B  = M_E_CPU1_SB_DQ<23>
  VSS121  = GND
  DQ26_B  = M_E_CPU1_SB_DQ<26>
  VSS122  = GND
  DQ27_B  = M_E_CPU1_SB_DQ<27>
  VSS123  = GND
  \dqs8_b_c||tdqs8_b_c\  = M_E_CPU1_SB_DQS_DN<8>
  \dqs8_b_t||tdqs8_b_t\  = M_E_CPU1_SB_DQS_DP<8>
  VSS124  = GND
  DQ30_B  = M_E_CPU1_SB_DQ<30>
  VSS125  = GND
  DQ31_B  = M_E_CPU1_SB_DQ<31>
  VSS126  = GND
  G1  = GND
  G2  = GND
  G3  = GND

(kicad_pcb
	(version 20260206)
	(generator "pcbnew")
	(generator_version "10.0")
	(general
		(thickness 1.6)
		(legacy_teardrops no)
	)
	(paper "A4")
	(title_block
		(title "03242023_DA0F0TMBIJ0_F0T_Motherboard_J_brd_V01_OCP.brd")
		(comment 1 "Grand Teton / footprint 1065 of 6105 (J26), pads 1-45 of 291")
	)
	(layers
		(0 "F.Cu" signal "TOP")
		(4 "In1.Cu" signal "GND")
		(6 "In2.Cu" signal "IN1")
		(8 "In3.Cu" signal "GND1")
		(10 "In4.Cu" signal "IN2")
		(12 "In5.Cu" signal "GND2")
		(14 "In6.Cu" signal "IN3")
		(16 "In7.Cu" signal "GND3")
		(18 "In8.Cu" signal "VCC")
		(20 "In9.Cu" signal "VCC1")
		(22 "In10.Cu" signal "GND4")
		(24 "In11.Cu" signal "IN4")
		(26 "In12.Cu" signal "GND5")
		(28 "In13.Cu" signal "IN5")
		(30 "In14.Cu" signal "GND6")
		(32 "In15.Cu" signal "IN6")
		(34 "In16.Cu" signal "GND7")
		(2 "B.Cu" signal "BOTTOM")
		(9 "F.Adhes" user "F.Adhesive")
		(11 "B.Adhes" user "B.Adhesive")
		(13 "F.Paste" user "Package Geometry/Pastemask Top")
		(15 "B.Paste" user "Package Geometry/Pastemask Bottom")
		(5 "F.SilkS" user "Ref Des/Silkscreen Top")
		(7 "B.SilkS" user "Ref Des/Silkscreen Bottom")
		(1 "F.Mask" user "Board Geometry/Soldermask Top")
		(3 "B.Mask" user "Board Geometry/Soldermask Bottom")
		(17 "Dwgs.User" user "User.Drawings")
		(19 "Cmts.User" user "User.Comments")
		(21 "Eco1.User" user "User.Eco1")
		(23 "Eco2.User" user "User.Eco2")
		(25 "Edge.Cuts" user "Board Geometry/Outline")
		(27 "Margin" user)
		(31 "F.CrtYd" user "Package Geometry/Place Bound Top")
		(29 "B.CrtYd" user "Package Geometry/Place Bound Bottom")
		(35 "F.Fab" user "Ref Des/Assembly Top")
		(33 "B.Fab" user "Ref Des/Assembly Bottom")
	)
	(footprint ""
		(layer "F.Cu")
		(at 160.86328 -258.091686)
		(property "Reference" "J26"
			(at -3.683 -81.702148 0)
			(unlocked yes)
			(layer "F.SilkS")
			(effects
				(font
					(size 0.7874 0.5842)
					(thickness 0.1524)
				)
				(justify left)
			)
		)
		(property "Value" ""
			(at 0 0 0)
			(layer "F.Fab")
			(effects
				(font
					(size 1.27 1.27)
				)
			)
		)
		(duplicate_pad_numbers_are_jumpers no)
		(pad "1" smd rect
			(at -2.050034 -63.324994 270)
			(size 0.519938 1.4986)
			(layers "F.Cu" "F.Mask" "F.Paste")
			(net "P12V_S3_AUX_CPU1_NVDIMM")
		)
		(pad "2" smd rect
			(at -2.050034 -62.47511 270)
			(size 0.519938 1.4986)
			(layers "F.Cu" "F.Mask" "F.Paste")
			(net "TP_CHE_CPU1_DIMM2_FRU_0")
		)
		(pad "3" smd rect
			(at -2.050034 -61.624972 270)
			(size 0.519938 1.4986)
			(layers "F.Cu" "F.Mask" "F.Paste")
			(net "P3V3_AUX")
		)
		(pad "4" smd rect
			(at -2.050034 -60.775088 270)
			(size 0.519938 1.4986)
			(layers "F.Cu" "F.Mask" "F.Paste")
			(net "I3C_SPD_DDREFGH_CPU1_LVC1_SCL_1")
		)
		(pad "5" smd rect
			(at -2.050034 -59.92495 270)
			(size 0.519938 1.4986)
			(layers "F.Cu" "F.Mask" "F.Paste")
			(net "I3C_SPD_DDREFGH_CPU1_LVC1_SDA")
		)
		(pad "6" smd rect
			(at -2.050034 -59.075066 270)
			(size 0.519938 1.4986)
			(layers "F.Cu" "F.Mask" "F.Paste")
			(net "GND")
		)
		(pad "7" smd rect
			(at -2.050034 -58.224928 270)
			(size 0.519938 1.4986)
			(layers "F.Cu" "F.Mask" "F.Paste")
			(net "M_E_CPU1_SA_DQ<0>")
		)
		(pad "8" smd rect
			(at -2.050034 -57.375044 270)
			(size 0.519938 1.4986)
			(layers "F.Cu" "F.Mask" "F.Paste")
			(net "GND")
		)
		(pad "9" smd rect
			(at -2.050034 -56.524906 270)
			(size 0.519938 1.4986)
			(layers "F.Cu" "F.Mask" "F.Paste")
			(net "M_E_CPU1_SA_DQ<1>")
		)
		(pad "10" smd rect
			(at -2.050034 -55.675022 270)
			(size 0.519938 1.4986)
			(layers "F.Cu" "F.Mask" "F.Paste")
			(net "GND")
		)
		(pad "11" smd rect
			(at -2.050034 -54.824884 270)
			(size 0.519938 1.4986)
			(layers "F.Cu" "F.Mask" "F.Paste")
			(net "M_E_CPU1_SA_DQS_DP<0>")
		)
		(pad "12" smd rect
			(at -2.050034 -53.975 270)
			(size 0.519938 1.4986)
			(layers "F.Cu" "F.Mask" "F.Paste")
			(net "M_E_CPU1_SA_DQS_DN<0>")
		)
		(pad "13" smd rect
			(at -2.050034 -53.125116 270)
			(size 0.519938 1.4986)
			(layers "F.Cu" "F.Mask" "F.Paste")
			(net "GND")
		)
		(pad "14" smd rect
			(at -2.050034 -52.274978 270)
			(size 0.519938 1.4986)
			(layers "F.Cu" "F.Mask" "F.Paste")
			(net "M_E_CPU1_SA_DQ<4>")
		)
		(pad "15" smd rect
			(at -2.050034 -51.425094 270)
			(size 0.519938 1.4986)
			(layers "F.Cu" "F.Mask" "F.Paste")
			(net "GND")
		)
		(pad "16" smd rect
			(at -2.050034 -50.574956 270)
			(size 0.519938 1.4986)
			(layers "F.Cu" "F.Mask" "F.Paste")
			(net "M_E_CPU1_SA_DQ<5>")
		)
		(pad "17" smd rect
			(at -2.050034 -49.725072 270)
			(size 0.519938 1.4986)
			(layers "F.Cu" "F.Mask" "F.Paste")
			(net "GND")
		)
		(pad "18" smd rect
			(at -2.050034 -48.874934 270)
			(size 0.519938 1.4986)
			(layers "F.Cu" "F.Mask" "F.Paste")
			(net "M_E_CPU1_SA_DQ<8>")
		)
		(pad "19" smd rect
			(at -2.050034 -48.02505 270)
			(size 0.519938 1.4986)
			(layers "F.Cu" "F.Mask" "F.Paste")
			(net "GND")
		)
		(pad "20" smd rect
			(at -2.050034 -47.174912 270)
			(size 0.519938 1.4986)
			(layers "F.Cu" "F.Mask" "F.Paste")
			(net "M_E_CPU1_SA_DQ<9>")
		)
		(pad "21" smd rect
			(at -2.050034 -46.325028 270)
			(size 0.519938 1.4986)
			(layers "F.Cu" "F.Mask" "F.Paste")
			(net "GND")
		)
		(pad "22" smd rect
			(at -2.050034 -45.47489 270)
			(size 0.519938 1.4986)
			(layers "F.Cu" "F.Mask" "F.Paste")
			(net "M_E_CPU1_SA_DQS_DP<1>")
		)
		(pad "23" smd rect
			(at -2.050034 -44.625006 270)
			(size 0.519938 1.4986)
			(layers "F.Cu" "F.Mask" "F.Paste")
			(net "M_E_CPU1_SA_DQS_DN<1>")
		)
		(pad "24" smd rect
			(at -2.050034 -43.775122 270)
			(size 0.519938 1.4986)
			(layers "F.Cu" "F.Mask" "F.Paste")
			(net "GND")
		)
		(pad "25" smd rect
			(at -2.050034 -42.924984 270)
			(size 0.519938 1.4986)
			(layers "F.Cu" "F.Mask" "F.Paste")
			(net "M_E_CPU1_SA_DQ<12>")
		)
		(pad "26" smd rect
			(at -2.050034 -42.0751 270)
			(size 0.519938 1.4986)
			(layers "F.Cu" "F.Mask" "F.Paste")
			(net "GND")
		)
		(pad "27" smd rect
			(at -2.050034 -41.224962 270)
			(size 0.519938 1.4986)
			(layers "F.Cu" "F.Mask" "F.Paste")
			(net "M_E_CPU1_SA_DQ<13>")
		)
		(pad "28" smd rect
			(at -2.050034 -40.375078 270)
			(size 0.519938 1.4986)
			(layers "F.Cu" "F.Mask" "F.Paste")
			(net "GND")
		)
		(pad "29" smd rect
			(at -2.050034 -39.52494 270)
			(size 0.519938 1.4986)
			(layers "F.Cu" "F.Mask" "F.Paste")
			(net "M_E_CPU1_SA_DQ<16>")
		)
		(pad "30" smd rect
			(at -2.050034 -38.675056 270)
			(size 0.519938 1.4986)
			(layers "F.Cu" "F.Mask" "F.Paste")
			(net "GND")
		)
		(pad "31" smd rect
			(at -2.050034 -37.824918 270)
			(size 0.519938 1.4986)
			(layers "F.Cu" "F.Mask" "F.Paste")
			(net "M_E_CPU1_SA_DQ<17>")
		)
		(pad "32" smd rect
			(at -2.050034 -36.975034 270)
			(size 0.519938 1.4986)
			(layers "F.Cu" "F.Mask" "F.Paste")
			(net "GND")
		)
		(pad "33" smd rect
			(at -2.050034 -36.124896 270)
			(size 0.519938 1.4986)
			(layers "F.Cu" "F.Mask" "F.Paste")
			(net "M_E_CPU1_SA_DQS_DP<2>")
		)
		(pad "34" smd rect
			(at -2.050034 -35.275012 270)
			(size 0.519938 1.4986)
			(layers "F.Cu" "F.Mask" "F.Paste")
			(net "M_E_CPU1_SA_DQS_DN<2>")
		)
		(pad "35" smd rect
			(at -2.050034 -34.425128 270)
			(size 0.519938 1.4986)
			(layers "F.Cu" "F.Mask" "F.Paste")
			(net "GND")
		)
		(pad "36" smd rect
			(at -2.050034 -33.57499 270)
			(size 0.519938 1.4986)
			(layers "F.Cu" "F.Mask" "F.Paste")
			(net "M_E_CPU1_SA_DQ<20>")
		)
		(pad "37" smd rect
			(at -2.050034 -32.725106 270)
			(size 0.519938 1.4986)
			(layers "F.Cu" "F.Mask" "F.Paste")
			(net "GND")
		)
		(pad "38" smd rect
			(at -2.050034 -31.874968 270)
			(size 0.519938 1.4986)
			(layers "F.Cu" "F.Mask" "F.Paste")
			(net "M_E_CPU1_SA_DQ<21>")
		)
		(pad "39" smd rect
			(at -2.050034 -31.025084 270)
			(size 0.519938 1.4986)
			(layers "F.Cu" "F.Mask" "F.Paste")
			(net "GND")
		)
		(pad "40" smd rect
			(at -2.050034 -30.174946 270)
			(size 0.519938 1.4986)
			(layers "F.Cu" "F.Mask" "F.Paste")
			(net "M_E_CPU1_SA_DQ<24>")
		)
		(pad "41" smd rect
			(at -2.050034 -29.325062 270)
			(size 0.519938 1.4986)
			(layers "F.Cu" "F.Mask" "F.Paste")
			(net "GND")
		)
		(pad "42" smd rect
			(at -2.050034 -28.474924 270)
			(size 0.519938 1.4986)
			(layers "F.Cu" "F.Mask" "F.Paste")
			(net "M_E_CPU1_SA_DQ<25>")
		)
		(pad "43" smd rect
			(at -2.050034 -27.62504 270)
			(size 0.519938 1.4986)
			(layers "F.Cu" "F.Mask" "F.Paste")
			(net "GND")
		)
		(pad "44" smd rect
			(at -2.050034 -26.774902 270)
			(size 0.519938 1.4986)
			(layers "F.Cu" "F.Mask" "F.Paste")
			(net "M_E_CPU1_SA_DQS_DP<3>")
		)
		(pad "45" smd rect
			(at -2.050034 -25.925018 270)
			(size 0.519938 1.4986)
			(layers "F.Cu" "F.Mask" "F.Paste")
			(net "M_E_CPU1_SA_DQS_DN<3>")
		)
	)
)
